# S9S_MB_2U (Grand Teton) — schematic netlist excerpt (pin names and nets, part order shuffled) for the footprints in the layout excerpt that follows; sources: Cadence DE-HDL packaged netlist, KiCad conversion of 03242023_DA0F0TMBIJ0_F0T_Motherboard_J_brd_V01_OCP.brd

J1  SCONN288_ADR50017P130CC  SCONN288_ADR50017-P130CC IO  pkg DDR288S_1-1VXB  page 82
  VIN_BULK0  = P12V_S3_AUX_CPU0_NVDIMM
  RFU0  = TP_CHA_CPU0_DIMM1_FRU_0
  VIN_MGMT  = P3V3_AUX
  HSCL  = I3C_SPD_DDRABCD_CPU0_LVC1_SCL_R
  HSDA  = I3C_SPD_DDRABCD_CPU0_LVC1_SDA
  VSS0  = GND
  DQ0_A  = M_A_CPU0_SA_DQ<0>
  VSS1  = GND
  DQ1_A  = M_A_CPU0_SA_DQ<1>
  VSS2  = GND
  DQS0_A_T  = M_A_CPU0_SA_DQS_DP<0>
  DQS0_A_C  = M_A_CPU0_SA_DQS_DN<0>
  VSS3  = GND
  DQ4_A  = M_A_CPU0_SA_DQ<4>
  VSS4  = GND
  DQ5_A  = M_A_CPU0_SA_DQ<5>
  VSS5  = GND
  DQ8_A  = M_A_CPU0_SA_DQ<8>
  VSS6  = GND
  DQ9_A  = M_A_CPU0_SA_DQ<9>
  VSS7  = GND
  DQS1_A_T  = M_A_CPU0_SA_DQS_DP<1>
  DQS1_A_C  = M_A_CPU0_SA_DQS_DN<1>
  VSS8  = GND
  DQ12_A  = M_A_CPU0_SA_DQ<12>
  VSS9  = GND
  DQ13_A  = M_A_CPU0_SA_DQ<13>
  VSS10  = GND
  DQ16_A  = M_A_CPU0_SA_DQ<16>
  VSS11  = GND
  DQ17_A  = M_A_CPU0_SA_DQ<17>
  VSS12  = GND
  DQS2_A_T  = M_A_CPU0_SA_DQS_DP<2>
  DQS2_A_C  = M_A_CPU0_SA_DQS_DN<2>
  VSS13  = GND
  DQ20_A  = M_A_CPU0_SA_DQ<20>
  VSS14  = GND
  DQ21_A  = M_A_CPU0_SA_DQ<21>
  VSS15  = GND
  DQ24_A  = M_A_CPU0_SA_DQ<24>
  VSS16  = GND
  DQ25_A  = M_A_CPU0_SA_DQ<25>
  VSS17  = GND
  DQS3_A_T  = M_A_CPU0_SA_DQS_DP<3>
  DQS3_A_C  = M_A_CPU0_SA_DQS_DN<3>
  VSS18  = GND
  DQ28_A  = M_A_CPU0_SA_DQ<28>
  VSS19  = GND
  DQ29_A  = M_A_CPU0_SA_DQ<29>
  VSS20  = GND
  CB0_A  = M_A_CPU0_SA_CB<0>
  VSS21  = GND
  CB1_A  = M_A_CPU0_SA_CB<1>
  VSS22  = GND
  DQS4_A_T  = M_A_CPU0_SA_DQS_DP<4>
  DQS4_A_C  = M_A_CPU0_SA_DQS_DN<4>
  VSS23  = GND
  CB4_A  = M_A_CPU0_SA_CB<4>
  VSS24  = GND
  CB5_A  = M_A_CPU0_SA_CB<5>
  VSS25  = GND
  ALERT_N  = M_A_CPU0_ALERT_N
  VSS26  = GND
  CS0_A_N  = M_A_CPU0_SA_CS_N<0>
  VSS27  = GND
  CA0_A  = M_A_CPU0_SA_CA<0>
  VSS28  = GND
  CA2_A  = M_A_CPU0_SA_CA<2>
  VSS29  = GND
  CA4_A  = M_A_CPU0_SA_CA<4>
  VSS30  = GND
  CA6_A  = M_A_CPU0_SA_CA<6>
  VSS31  = GND
  PAR_A  = M_A_CPU0_SA_PAR
  VSS32  = GND
  CA0_B  = M_A_CPU0_SB_CA<0>
  VSS33  = GND
  CA2_B  = M_A_CPU0_SB_CA<2>
  VSS34  = GND
  CA4_B  = M_A_CPU0_SB_CA<4>
  VSS35  = GND
  CA6_B  = M_A_CPU0_SB_CA<6>
  VSS36  = GND
  CS0_B_N  = M_A_CPU0_SB_CS_N<0>
  VSS37  = GND
  \lbd||rsp_a_n\  = M_A_CPU0_SA_RSP<0>
  \lbs||rsp_b_n\  = M_A_CPU0_SB_RSP<0>
  VSS38  = GND
  CB4_B  = M_A_CPU0_SB_CB<4>
  VSS39  = GND
  CB5_B  = M_A_CPU0_SB_CB<5>
  VSS40  = GND
  \dqs9_b_t||tdqs9_b_t||dbi4_b_n\  = M_A_CPU0_SB_DQS_DP<9>
  \dqs9_b_c||tdqs9_b_c\  = M_A_CPU0_SB_DQS_DN<9>
  VSS41  = GND
  CB0_B  = M_A_CPU0_SB_CB<0>
  VSS42  = GND
  CB1_B  = M_A_CPU0_SB_CB<1>
  VSS43  = GND
  DQ0_B  = M_A_CPU0_SB_DQ<0>
  VSS44  = GND
  DQ1_B  = M_A_CPU0_SB_DQ<1>
  VSS45  = GND
  DQS0_B_T  = M_A_CPU0_SB_DQS_DP<0>
  DQS0_B_C  = M_A_CPU0_SB_DQS_DN<0>
  VSS46  = GND
  DQ4_B  = M_A_CPU0_SB_DQ<4>
  VSS47  = GND
  DQ5_B  = M_A_CPU0_SB_DQ<5>
  VSS48  = GND
  DQ8_B  = M_A_CPU0_SB_DQ<8>
  VSS49  = GND
  DQ9_B  = M_A_CPU0_SB_DQ<9>
  VSS50  = GND
  DQS1_B_T  = M_A_CPU0_SB_DQS_DP<1>
  DQS1_B_C  = M_A_CPU0_SB_DQS_DN<1>
  VSS51  = GND
  DQ12_B  = M_A_CPU0_SB_DQ<12>
  VSS52  = GND
  DQ13_B  = M_A_CPU0_SB_DQ<13>
  VSS53  = GND
  DQ16_B  = M_A_CPU0_SB_DQ<16>
  VSS54  = GND
  DQ17_B  = M_A_CPU0_SB_DQ<17>
  VSS55  = GND
  DQS2_B_T  = M_A_CPU0_SB_DQS_DP<2>
  DQS2_B_C  = M_A_CPU0_SB_DQS_DN<2>
  VSS56  = GND
  DQ20_B  = M_A_CPU0_SB_DQ<20>
  VSS57  = GND
  DQ21_B  = M_A_CPU0_SB_DQ<21>
  VSS58  = GND
  DQ24_B  = M_A_CPU0_SB_DQ<24>
  VSS59  = GND
  DQ25_B  = M_A_CPU0_SB_DQ<25>
  VSS60  = GND
  DQS3_B_T  = M_A_CPU0_SB_DQS_DP<3>
  DQS3_B_C  = M_A_CPU0_SB_DQS_DN<3>
  VSS61  = GND
  DQ28_B  = M_A_CPU0_SB_DQ<28>
  VSS62  = GND
  DQ29_B  = M_A_CPU0_SB_DQ<29>
  VSS63  = GND
  RFU1  = TP_CHA_CPU0_DIMM1_FRU_1
  VIN_BULK1  = P12V_S3_AUX_CPU0_NVDIMM
  VIN_BULK2  = P12V_S3_AUX_CPU0_NVDIMM
  \pwr_good||fail_n\  = PWRGD_CHA_CPU0_DIMM1
  HSA  = PD_CHA_CPU0_DIMM1_SAA
  RFU2  = TP_CHA_CPU0_DIMM1_FRU_2
  RFU3  = TP_CHA_CPU0_DIMM1_FRU_3
  VSS64  = GND
  DQ2_A  = M_A_CPU0_SA_DQ<2>
  VSS65  = GND
  DQ3_A  = M_A_CPU0_SA_DQ<3>
  VSS66  = GND
  \dqs5_a_c||tdqs5_a_c||dqs5_a_t||tdqs5_a_t\  = M_A_CPU0_SA_DQS_DN<5>
  \dqs5_a_t||tdqs5_a_t\  = M_A_CPU0_SA_DQS_DP<5>
  VSS67  = GND
  DQ6_A  = M_A_CPU0_SA_DQ<6>
  VSS68  = GND
  DQ7_A  = M_A_CPU0_SA_DQ<7>
  VSS69  = GND
  DQ10_A  = M_A_CPU0_SA_DQ<10>
  VSS70  = GND
  DQ11_A  = M_A_CPU0_SA_DQ<11>
  VSS71  = GND
  \dqs6_a_c||tdqs6_a_c||dqs6_a_t||tdqs6_a_t\  = M_A_CPU0_SA_DQS_DN<6>
  \dqs6_a_t||tdqs6_a_t\  = M_A_CPU0_SA_DQS_DP<6>
  VSS72  = GND
  DQ14_A  = M_A_CPU0_SA_DQ<14>
  VSS73  = GND
  DQ15_A  = M_A_CPU0_SA_DQ<15>
  VSS74  = GND
  DQ18_A  = M_A_CPU0_SA_DQ<18>
  VSS75  = GND
  DQ19_A  = M_A_CPU0_SA_DQ<19>
  VSS76  = GND
  \dqs7_a_c||tdqs7_a_c\  = M_A_CPU0_SA_DQS_DN<7>
  \dqs7_a_t||tdqs7_a_t\  = M_A_CPU0_SA_DQS_DP<7>
  VSS77  = GND
  DQ22_A  = M_A_CPU0_SA_DQ<22>
  VSS78  = GND
  DQ23_A  = M_A_CPU0_SA_DQ<23>
  VSS79  = GND
  DQ26_A  = M_A_CPU0_SA_DQ<26>
  VSS80  = GND
  DQ27_A  = M_A_CPU0_SA_DQ<27>
  VSS81  = GND
  \dqs8_a_c||tdqs8_a_c\  = M_A_CPU0_SA_DQS_DN<8>
  \dqs8_a_t||tdqs8_a_t\  = M_A_CPU0_SA_DQS_DP<8>
  VSS82  = GND
  DQ30_A  = M_A_CPU0_SA_DQ<30>
  VSS83  = GND
  DQ31_A  = M_A_CPU0_SA_DQ<31>
  VSS84  = GND
  CB2_A  = M_A_CPU0_SA_CB<2>
  VSS85  = GND
  CB3_A  = M_A_CPU0_SA_CB<3>
  VSS86  = GND
  \dqs9_a_c||tdqs9_a_c\  = M_A_CPU0_SA_DQS_DN<9>
  \dqs9_a_t||tdqs9_a_t\  = M_A_CPU0_SA_DQS_DP<9>
  VSS87  = GND
  CB6_A  = M_A_CPU0_SA_CB<6>
  VSS88  = GND
  CB7_A  = M_A_CPU0_SA_CB<7>
  VSS89  = GND
  RESET_N  = RST_M_AB_CPU0_FPGA_N
  VSS90  = GND
  CS1_A_N  = M_A_CPU0_SA_CS_N<1>
  VSS91  = GND
  CA1_A  = M_A_CPU0_SA_CA<1>
  VSS92  = GND
  CA3_A  = M_A_CPU0_SA_CA<3>
  VSS93  = GND
  CA5_A  = M_A_CPU0_SA_CA<5>
  VSS94  = GND
  CK_T  = M_A_CPU0_CLK_DP<0>
  CK_C  = M_A_CPU0_CLK_DN<0>
  VSS95  = GND
  RFU4  = TP_CHA_CPU0_DIMM1_FRU_4
  CA1_B  = M_A_CPU0_SB_CA<1>
  VSS96  = GND
  CA3_B  = M_A_CPU0_SB_CA<3>
  VSS97  = GND
  CA5_B  = M_A_CPU0_SB_CA<5>
  VSS98  = GND
  PAR_B  = M_A_CPU0_SB_PAR
  VSS99  = GND
  CS1_B_N  = M_A_CPU0_SB_CS_N<1>
  VSS100  = GND
  RFU5  = TP_CHA_CPU0_DIMM1_FRU_5
  RFU6  = TP_CHA_CPU0_DIMM1_FRU_6
  VSS101  = GND
  CB6_B  = M_A_CPU0_SB_CB<6>
  VSS102  = GND
  CB7_B  = M_A_CPU0_SB_CB<7>
  VSS103  = GND
  DQS4_B_C  = M_A_CPU0_SB_DQS_DN<4>
  DQS4_B_T  = M_A_CPU0_SB_DQS_DP<4>
  VSS104  = GND
  CB2_B  = M_A_CPU0_SB_CB<2>
  VSS105  = GND
  CB3_B  = M_A_CPU0_SB_CB<3>
  VSS106  = GND
  DQ2_B  = M_A_CPU0_SB_DQ<2>
  VSS107  = GND
  DQ3_B  = M_A_CPU0_SB_DQ<3>
  VSS108  = GND
  \dqs5_b_c||tdqs5_b_c\  = M_A_CPU0_SB_DQS_DN<5>
  \dqs5_b_t||tdqs5_b_t\  = M_A_CPU0_SB_DQS_DP<5>
  VSS109  = GND
  DQ6_B  = M_A_CPU0_SB_DQ<6>
  VSS110  = GND
  DQ7_B  = M_A_CPU0_SB_DQ<7>
  VSS111  = GND
  DQ10_B  = M_A_CPU0_SB_DQ<10>
  VSS112  = GND
  DQ11_B  = M_A_CPU0_SB_DQ<11>
  VSS113  = GND
  \dqs6_b_c||tdqs6_b_c\  = M_A_CPU0_SB_DQS_DN<6>
  \dqs6_b_t||tdqs6_b_t\  = M_A_CPU0_SB_DQS_DP<6>
  VSS114  = GND
  DQ14_B  = M_A_CPU0_SB_DQ<14>
  VSS115  = GND
  DQ15_B  = M_A_CPU0_SB_DQ<15>
  VSS116  = GND
  DQ18_B  = M_A_CPU0_SB_DQ<18>
  VSS117  = GND
  DQ19_B  = M_A_CPU0_SB_DQ<19>
  VSS118  = GND
  \dqs7_b_c||tdqs7_b_c\  = M_A_CPU0_SB_DQS_DN<7>
  \dqs7_b_t||tdqs7_b_t\  = M_A_CPU0_SB_DQS_DP<7>
  VSS119  = GND
  DQ22_B  = M_A_CPU0_SB_DQ<22>
  VSS120  = GND
  DQ23_B  = M_A_CPU0_SB_DQ<23>
  VSS121  = GND
  DQ26_B  = M_A_CPU0_SB_DQ<26>
  VSS122  = GND
  DQ27_B  = M_A_CPU0_SB_DQ<27>
  VSS123  = GND
  \dqs8_b_c||tdqs8_b_c\  = M_A_CPU0_SB_DQS_DN<8>
  \dqs8_b_t||tdqs8_b_t\  = M_A_CPU0_SB_DQS_DP<8>
  VSS124  = GND
  DQ30_B  = M_A_CPU0_SB_DQ<30>
  VSS125  = GND
  DQ31_B  = M_A_CPU0_SB_DQ<31>
  VSS126  = GND
  G1  = GND
  G2  = GND
  G3  = GND

(kicad_pcb
	(version 20260206)
	(generator "pcbnew")
	(generator_version "10.0")
	(general
		(thickness 1.6)
		(legacy_teardrops no)
	)
	(paper "A4")
	(title_block
		(title "03242023_DA0F0TMBIJ0_F0T_Motherboard_J_brd_V01_OCP.brd")
		(comment 1 "Grand Teton / footprint 1236 of 6105 (J1), pads 138-182 of 291")
	)
	(layers
		(0 "F.Cu" signal "TOP")
		(4 "In1.Cu" signal "GND")
		(6 "In2.Cu" signal "IN1")
		(8 "In3.Cu" signal "GND1")
		(10 "In4.Cu" signal "IN2")
		(12 "In5.Cu" signal "GND2")
		(14 "In6.Cu" signal "IN3")
		(16 "In7.Cu" signal "GND3")
		(18 "In8.Cu" signal "VCC")
		(20 "In9.Cu" signal "VCC1")
		(22 "In10.Cu" signal "GND4")
		(24 "In11.Cu" signal "IN4")
		(26 "In12.Cu" signal "GND5")
		(28 "In13.Cu" signal "IN5")
		(30 "In14.Cu" signal "GND6")
		(32 "In15.Cu" signal "IN6")
		(34 "In16.Cu" signal "GND7")
		(2 "B.Cu" signal "BOTTOM")
		(9 "F.Adhes" user "F.Adhesive")
		(11 "B.Adhes" user "B.Adhesive")
		(13 "F.Paste" user "Package Geometry/Pastemask Top")
		(15 "B.Paste" user "Package Geometry/Pastemask Bottom")
		(5 "F.SilkS" user "Ref Des/Silkscreen Top")
		(7 "B.SilkS" user "Ref Des/Silkscreen Bottom")
		(1 "F.Mask" user "Board Geometry/Soldermask Top")
		(3 "B.Mask" user "Board Geometry/Soldermask Bottom")
		(17 "Dwgs.User" user "User.Drawings")
		(19 "Cmts.User" user "User.Comments")
		(21 "Eco1.User" user "User.Eco1")
		(23 "Eco2.User" user "User.Eco2")
		(25 "Edge.Cuts" user "Board Geometry/Outline")
		(27 "Margin" user)
		(31 "F.CrtYd" user "Package Geometry/Place Bound Top")
		(29 "B.CrtYd" user "Package Geometry/Place Bound Bottom")
		(35 "F.Fab" user "Ref Des/Assembly Top")
		(33 "B.Fab" user "Ref Des/Assembly Bottom")
	)
	(footprint ""
		(layer "F.Cu")
		(at 303.393348 -258.091686)
		(property "Reference" "J1"
			(at -3.683 -81.702148 0)
			(unlocked yes)
			(layer "F.SilkS")
			(effects
				(font
					(size 0.7874 0.5842)
					(thickness 0.1524)
				)
				(justify left)
			)
		)
		(property "Value" ""
			(at 0 0 0)
			(layer "F.Fab")
			(effects
				(font
					(size 1.27 1.27)
				)
			)
		)
		(duplicate_pad_numbers_are_jumpers no)
		(pad "138" smd rect
			(at -2.050034 58.224928 270)
			(size 0.519938 1.4986)
			(layers "F.Cu" "F.Mask" "F.Paste")
			(net "M_A_CPU0_SB_DQS_DN<3>")
		)
		(pad "139" smd rect
			(at -2.050034 59.075066 270)
			(size 0.519938 1.4986)
			(layers "F.Cu" "F.Mask" "F.Paste")
			(net "GND")
		)
		(pad "140" smd rect
			(at -2.050034 59.92495 270)
			(size 0.519938 1.4986)
			(layers "F.Cu" "F.Mask" "F.Paste")
			(net "M_A_CPU0_SB_DQ<28>")
		)
		(pad "141" smd rect
			(at -2.050034 60.775088 270)
			(size 0.519938 1.4986)
			(layers "F.Cu" "F.Mask" "F.Paste")
			(net "GND")
		)
		(pad "142" smd rect
			(at -2.050034 61.624972 270)
			(size 0.519938 1.4986)
			(layers "F.Cu" "F.Mask" "F.Paste")
			(net "M_A_CPU0_SB_DQ<29>")
		)
		(pad "143" smd rect
			(at -2.050034 62.47511 270)
			(size 0.519938 1.4986)
			(layers "F.Cu" "F.Mask" "F.Paste")
			(net "GND")
		)
		(pad "144" smd rect
			(at -2.050034 63.324994 270)
			(size 0.519938 1.4986)
			(layers "F.Cu" "F.Mask" "F.Paste")
			(net "TP_CHA_CPU0_DIMM1_FRU_1")
		)
		(pad "145" smd rect
			(at 2.050034 -63.324994 270)
			(size 0.519938 1.4986)
			(layers "F.Cu" "F.Mask" "F.Paste")
			(net "P12V_S3_AUX_CPU0_NVDIMM")
		)
		(pad "146" smd rect
			(at 2.050034 -62.47511 270)
			(size 0.519938 1.4986)
			(layers "F.Cu" "F.Mask" "F.Paste")
			(net "P12V_S3_AUX_CPU0_NVDIMM")
		)
		(pad "147" smd rect
			(at 2.050034 -61.624972 270)
			(size 0.519938 1.4986)
			(layers "F.Cu" "F.Mask" "F.Paste")
			(net "PWRGD_CHA_CPU0_DIMM1")
		)
		(pad "148" smd rect
			(at 2.050034 -60.775088 270)
			(size 0.519938 1.4986)
			(layers "F.Cu" "F.Mask" "F.Paste")
			(net "PD_CHA_CPU0_DIMM1_SAA")
		)
		(pad "149" smd rect
			(at 2.050034 -59.92495 270)
			(size 0.519938 1.4986)
			(layers "F.Cu" "F.Mask" "F.Paste")
			(net "TP_CHA_CPU0_DIMM1_FRU_2")
		)
		(pad "150" smd rect
			(at 2.050034 -59.075066 270)
			(size 0.519938 1.4986)
			(layers "F.Cu" "F.Mask" "F.Paste")
			(net "TP_CHA_CPU0_DIMM1_FRU_3")
		)
		(pad "151" smd rect
			(at 2.050034 -58.224928 270)
			(size 0.519938 1.4986)
			(layers "F.Cu" "F.Mask" "F.Paste")
			(net "GND")
		)
		(pad "152" smd rect
			(at 2.050034 -57.375044 270)
			(size 0.519938 1.4986)
			(layers "F.Cu" "F.Mask" "F.Paste")
			(net "M_A_CPU0_SA_DQ<2>")
		)
		(pad "153" smd rect
			(at 2.050034 -56.524906 270)
			(size 0.519938 1.4986)
			(layers "F.Cu" "F.Mask" "F.Paste")
			(net "GND")
		)
		(pad "154" smd rect
			(at 2.050034 -55.675022 270)
			(size 0.519938 1.4986)
			(layers "F.Cu" "F.Mask" "F.Paste")
			(net "M_A_CPU0_SA_DQ<3>")
		)
		(pad "155" smd rect
			(at 2.050034 -54.824884 270)
			(size 0.519938 1.4986)
			(layers "F.Cu" "F.Mask" "F.Paste")
			(net "GND")
		)
		(pad "156" smd rect
			(at 2.050034 -53.975 270)
			(size 0.519938 1.4986)
			(layers "F.Cu" "F.Mask" "F.Paste")
			(net "M_A_CPU0_SA_DQS_DN<5>")
		)
		(pad "157" smd rect
			(at 2.050034 -53.125116 270)
			(size 0.519938 1.4986)
			(layers "F.Cu" "F.Mask" "F.Paste")
			(net "M_A_CPU0_SA_DQS_DP<5>")
		)
		(pad "158" smd rect
			(at 2.050034 -52.274978 270)
			(size 0.519938 1.4986)
			(layers "F.Cu" "F.Mask" "F.Paste")
			(net "GND")
		)
		(pad "159" smd rect
			(at 2.050034 -51.425094 270)
			(size 0.519938 1.4986)
			(layers "F.Cu" "F.Mask" "F.Paste")
			(net "M_A_CPU0_SA_DQ<6>")
		)
		(pad "160" smd rect
			(at 2.050034 -50.574956 270)
			(size 0.519938 1.4986)
			(layers "F.Cu" "F.Mask" "F.Paste")
			(net "GND")
		)
		(pad "161" smd rect
			(at 2.050034 -49.725072 270)
			(size 0.519938 1.4986)
			(layers "F.Cu" "F.Mask" "F.Paste")
			(net "M_A_CPU0_SA_DQ<7>")
		)
		(pad "162" smd rect
			(at 2.050034 -48.874934 270)
			(size 0.519938 1.4986)
			(layers "F.Cu" "F.Mask" "F.Paste")
			(net "GND")
		)
		(pad "163" smd rect
			(at 2.050034 -48.02505 270)
			(size 0.519938 1.4986)
			(layers "F.Cu" "F.Mask" "F.Paste")
			(net "M_A_CPU0_SA_DQ<10>")
		)
		(pad "164" smd rect
			(at 2.050034 -47.174912 270)
			(size 0.519938 1.4986)
			(layers "F.Cu" "F.Mask" "F.Paste")
			(net "GND")
		)
		(pad "165" smd rect
			(at 2.050034 -46.325028 270)
			(size 0.519938 1.4986)
			(layers "F.Cu" "F.Mask" "F.Paste")
			(net "M_A_CPU0_SA_DQ<11>")
		)
		(pad "166" smd rect
			(at 2.050034 -45.47489 270)
			(size 0.519938 1.4986)
			(layers "F.Cu" "F.Mask" "F.Paste")
			(net "GND")
		)
		(pad "167" smd rect
			(at 2.050034 -44.625006 270)
			(size 0.519938 1.4986)
			(layers "F.Cu" "F.Mask" "F.Paste")
			(net "M_A_CPU0_SA_DQS_DN<6>")
		)
		(pad "168" smd rect
			(at 2.050034 -43.775122 270)
			(size 0.519938 1.4986)
			(layers "F.Cu" "F.Mask" "F.Paste")
			(net "M_A_CPU0_SA_DQS_DP<6>")
		)
		(pad "169" smd rect
			(at 2.050034 -42.924984 270)
			(size 0.519938 1.4986)
			(layers "F.Cu" "F.Mask" "F.Paste")
			(net "GND")
		)
		(pad "170" smd rect
			(at 2.050034 -42.0751 270)
			(size 0.519938 1.4986)
			(layers "F.Cu" "F.Mask" "F.Paste")
			(net "M_A_CPU0_SA_DQ<14>")
		)
		(pad "171" smd rect
			(at 2.050034 -41.224962 270)
			(size 0.519938 1.4986)
			(layers "F.Cu" "F.Mask" "F.Paste")
			(net "GND")
		)
		(pad "172" smd rect
			(at 2.050034 -40.375078 270)
			(size 0.519938 1.4986)
			(layers "F.Cu" "F.Mask" "F.Paste")
			(net "M_A_CPU0_SA_DQ<15>")
		)
		(pad "173" smd rect
			(at 2.050034 -39.52494 270)
			(size 0.519938 1.4986)
			(layers "F.Cu" "F.Mask" "F.Paste")
			(net "GND")
		)
		(pad "174" smd rect
			(at 2.050034 -38.675056 270)
			(size 0.519938 1.4986)
			(layers "F.Cu" "F.Mask" "F.Paste")
			(net "M_A_CPU0_SA_DQ<18>")
		)
		(pad "175" smd rect
			(at 2.050034 -37.824918 270)
			(size 0.519938 1.4986)
			(layers "F.Cu" "F.Mask" "F.Paste")
			(net "GND")
		)
		(pad "176" smd rect
			(at 2.050034 -36.975034 270)
			(size 0.519938 1.4986)
			(layers "F.Cu" "F.Mask" "F.Paste")
			(net "M_A_CPU0_SA_DQ<19>")
		)
		(pad "177" smd rect
			(at 2.050034 -36.124896 270)
			(size 0.519938 1.4986)
			(layers "F.Cu" "F.Mask" "F.Paste")
			(net "GND")
		)
		(pad "178" smd rect
			(at 2.050034 -35.275012 270)
			(size 0.519938 1.4986)
			(layers "F.Cu" "F.Mask" "F.Paste")
			(net "M_A_CPU0_SA_DQS_DN<7>")
		)
		(pad "179" smd rect
			(at 2.050034 -34.425128 270)
			(size 0.519938 1.4986)
			(layers "F.Cu" "F.Mask" "F.Paste")
			(net "M_A_CPU0_SA_DQS_DP<7>")
		)
		(pad "180" smd rect
			(at 2.050034 -33.57499 270)
			(size 0.519938 1.4986)
			(layers "F.Cu" "F.Mask" "F.Paste")
			(net "GND")
		)
		(pad "181" smd rect
			(at 2.050034 -32.725106 270)
			(size 0.519938 1.4986)
			(layers "F.Cu" "F.Mask" "F.Paste")
			(net "M_A_CPU0_SA_DQ<22>")
		)
		(pad "182" smd rect
			(at 2.050034 -31.874968 270)
			(size 0.519938 1.4986)
			(layers "F.Cu" "F.Mask" "F.Paste")
			(net "GND")
		)
	)
)
